FILE_TYPE = CONNECTIVITY;
{Allegro Design Entry HDL 17.2-2016 S081 (4005846) 1/11/2022}
"PAGE_NUMBER" = 168;
0"NC";
1"GND\g";
2"GND\g";
3"GND\g";
4"GND\g";
5"GND\g";
6"GND\g";
7"GND\g";
8"GND\g";
9"GND\g";
10"GND\g";
11"GND\g";
12"GND\g";
13"GND\g";
14"GND\g";
15"GND\g";
16"GND\g";
17"GND\g";
18"GND\g";
19"PVDDCR_CPU0_P0\g";
20"PVDDCR_SOC_P0\g";
21"GND\g";
22"VSENSE_VSS_SENSE_A_P0";
23"VSENSE_PVDDCR_SOC_P0_DP";
24"VSENSE_VSS_SENSE_A_P0";
25"VSENSE_PVDDCR_CPU0_P0_DP";
26"PVDDCR_SOC_P0_PWM3";
27"PVDDCR_SOC_P0_EN//ADDR_CFG";
28"NC_PVDDCR_CPU0_P0_IMON7";
29"PVDDCR_CPU0_P0_IMON6";
30"PVDDCR_CPU0_P0_PWM6";
31"PWRGD_PVDDCR_SOC_P0_R";
32"PVDDCR_CPU0_P0_VINSEN";
33"PVDDCR_SOC_P0_IMON3";
34"NC_PVDDCR_CPU0_P0_IMON9";
35"NC_PVDDCR_CPU0_P0_PWM9";
36"PWRGD_PVDDCR_CPU0_P0_R";
37"VSENSE_PVDDCR_CPU0_P0_VSEN0";
38"PVDDCR_SOC_P0_IMON1";
39"PVDDCR_SOC_P0_TEMP1";
40"SVID_PVDDCR_CPU0_P0_SVC_R";
41"PVDDCR_CPU0_P0_EN_R";
42"SVID_PVDDCR_CPU0_P0_SVD_R";
43"SVID_PVDDCR_CPU0_P0_SVTO_R";
44"SVID_PVDDCR_CPU0_P0_SVTI_R";
45"SMB_SCM_6_R3_SDA";
46"SMB_SCM_6_R3_SCL";
47"PVDDCR_SOC_P0_EN";
48"PVDDCR_CPU0_P0_EN";
49"PWRGD_PVDDCR_CPU0_P0";
50"NC_PVDDCR_CPU0_P0_PWM8";
51"PWRGD_PVDDCR_SOC_P0";
52"PVDDCR_CPU0_P0_PMALERT";
53"PVDDCR_CPU0_P0_IMON1";
54"PVDDCR_CPU0_P0_PWM2";
55"PVDDCR_CPU0_P0_IMON2";
56"SVID_PVDDCR_CPU0_P0_SVTO";
57"PVDDCR_CPU0_P0_PMSCL_R";
58"PVDDCR_CPU0_P0_PMALERT_R";
59"PVDDCR_CPU0_P0_PMSDA_R";
60"PVDDCR_CPU0_P0_RESET_N_R";
61"SVID_PVDDCR_CPU0_P0_SVTI";
62"PVDDCR_SOC_P0_EN_RC";
63"PVDDCR_SOC_P0_EN_GD";
64"PVDDCR_CPU0_P0_RESET_N";
65"PVDDCR_CPU0_P0_OCP_N";
66"PVDDCR_CPU0_P0_OCP_N_R";
67"VSENSE_PVDDCR_SOC_P0_VSEN1";
68"PVDDCR_CPU0_P0_TEMP0";
69"PVDDCR_SOC_P0_PWM1";
70"PVDDCR_SOC_P0_IMON2";
71"NC_PVDDCR_CPU0_P0_PWM7";
72"NC_PVDDCR_CPU0_P0_IMON8";
73"PVDDCR_SOC_P0_PWM2";
74"PVDDCR_CPU0_P0_IMON5";
75"PVDDCR_CPU0_P0_PWM5";
76"PVDDCR_CPU0_P0_VCCS";
77"PVDDCR_CPU0_P0_PWM1";
78"PVDDCR_CPU0_P0_PWM3";
79"PVDDCR_CPU0_P0_IMON3";
80"PVDDCR_CPU0_P0_PWM4";
81"PVDDCR_CPU0_P0_IMON4";
82"PVDDCR_CPU0_P0_VCC";
83"PVDDCR_CPU0_P0_VMON";
84"GND\g";
85"P3V3_STBY\g";
86"PVDD18_S5_P0\g";
87"GND\g";
88"GND\g";
89"P3V3_STBY\g";
90"GND\g";
91"GND\g";
92"GND\g";
93"GND\g";
94"PVDD18_S5_P0\g";
95"PVDD18_S5_P0\g";
96"P3V3_STBY\g";
97"GND\g";
98"GND\g";
99"P3V3_STBY\g";
100"P5V_STBY\g";
101"P12V_STBY\g";
%"MOSFET_N"
"1","(-7825,1525)","0","pure_quanta","I1";
;
LOCATION"PQ17"
$SEC"1"
CDS_SEC"1"
MATERIAL"IC"
VALUE"BSS138K"
PART_NUMBER"BAM138K0000"
MANUF_PN"BSS138K"
CDS_LIB"pure_quanta"
CDS_LMAN_SYM_OUTLINE"-50,50,100,-150"
PACK_TYPE"SMLF";
"GATE"
$PN"G"62;
"SOURCE"
$PN"S"88;
"DRAIN"
$PN"D"63;
%"UNIVERSAL_GND"
"1","(-2900,5875)","0","pure_quanta_power","I10";
;
CDS_LIB"pure_quanta_power"
HDL_POWER"GND";
"A"1;
%"Q_CAP"
"1","(-5300,475)","0","pure_quanta","I100";
;
LOCATION"PC7"
SEC"1"
PART_NUMBER"CH4104K1B00"
MATERIAL"X7R"
TOLERANCE"10%"
VALUE"0.1UF"
VOLTAGE"25V"
PACK_TYPE"0402"
CDS_LIB"pure_quanta"
SEC_TYPE"0402";
"B"
$PN"2"2;
"A"
$PN"1"32;
%"Q_RES"
"1","(-5975,650)","0","pure_quanta","I101";
;
LOCATION"PR314"
$SEC"1"
CDS_SEC"1"
MATERIAL"CHIP"
PART_NUMBER"CS00002JB38"
PACK_TYPE"0402LF"
WATTAGE"1/16W"
TOLERANCE"5%"
VALUE"0"
CDS_LIB"pure_quanta";
"B"
$PN"2"32;
"A"
$PN"1"101;
%"UNIVERSAL_GND"
"1","(-5300,250)","0","pure_quanta_power","I102";
;
CDS_LIB"pure_quanta_power"
HDL_POWER"GND";
"A"2;
%"VCC_CORE"
"1","(-6175,725)","0","pure_quanta_power","I103";
;
HDL_POWER"P12V_STBY"
CDS_LIB"pure_quanta_power";
"A"101;
%"Q_RES"
"1","(-7250,825)","0","pure_quanta","I104";
;
LOCATION"PR290"
$SEC"1"
CDS_SEC"1"
VALUE"40.2K"
PART_NUMBER"TMP_QCS34022FB15"
WATTAGE"1/16W"
MATERIAL"CHIP"
TOLERANCE"1%"
PACK_TYPE"0402LF"
CDS_LIB"pure_quanta";
"B"
$PN"2"83;
"A"
$PN"1"100;
%"Q_RES"
"2","(-6950,625)","0","pure_quanta","I105";
;
LOCATION"PR5"
SEC"1"
MATERIAL"CHIP"
PART_NUMBER"TMP_QCS31002FB26"
WATTAGE"1/16W"
TOLERANCE"1%"
VALUE"10K"
PACK_TYPE"0402LF"
SEC_TYPE"0402LF"
CDS_LIB"pure_quanta";
"A"
$PN"1"83;
"B"
$PN"2"3;
%"UNIVERSAL_GND"
"1","(-6950,400)","0","pure_quanta_power","I107";
;
CDS_LIB"pure_quanta_power"
HDL_POWER"GND";
"A"3;
%"UNIVERSAL_GND"
"1","(-6475,400)","0","pure_quanta_power","I108";
;
CDS_LIB"pure_quanta_power"
HDL_POWER"GND";
"A"4;
%"VCC_CORE"
"1","(-7550,950)","0","pure_quanta_power","I109";
;
HDL_POWER"P5V_STBY"
CDS_LIB"pure_quanta_power";
"A"100;
%"VCC_CORE"
"1","(-6600,1400)","0","pure_quanta_power","I111";
;
HDL_POWER"P3V3_STBY"
CDS_LIB"pure_quanta_power";
"A"99;
%"Q_RES"
"1","(-6325,1250)","0","pure_quanta","I112";
;
LOCATION"PR298"
$SEC"1"
CDS_SEC"1"
WATTAGE"1/16W"
MATERIAL"CHIP"
TOLERANCE"1%"
VALUE"1K"
PART_NUMBER"TMP_QCS21002FB24"
PACK_TYPE"0402LF"
CDS_LIB"pure_quanta";
"B"
$PN"2"31;
"A"
$PN"1"99;
%"Q_RES"
"1","(-6325,1000)","0","pure_quanta","I113";
;
LOCATION"PR299"
$SEC"1"
CDS_SEC"1"
PART_NUMBER"CS00002JB38"
PACK_TYPE"0402LF"
WATTAGE"1/16W"
MATERIAL"CHIP"
TOLERANCE"5%"
VALUE"0"
CDS_LIB"pure_quanta";
"B"
$PN"2"31;
"A"
$PN"1"51;
%"Q_CAP"
"2","(-5650,1250)","0","pure_quanta","I114";
;
LOCATION"PC465"
$SEC"1"
CDS_SEC"1"
TOLERANCE"5%"
MATERIAL"EMPTY"
VALUE"1000PF"
PART_NUMBER"TMP_QCH21006JB10"
VOLTAGE"50V"
PACK_TYPE"0402"
CDS_LIB"pure_quanta";
"A"
$PN"1"31;
"B"
$PN"2"98;
%"UNIVERSAL_GND"
"1","(-5325,1125)","0","pure_quanta_power","I116";
;
CDS_LIB"pure_quanta_power"
HDL_POWER"GND";
"A"98;
%"Q_CAP"
"1","(-6475,625)","0","pure_quanta","I118";
;
LOCATION"PC462"
$SEC"1"
CDS_SEC"1"
MATERIAL"X7R"
TOLERANCE"10%"
VALUE"0.1UF"
PART_NUMBER"CH4104K1B00"
VOLTAGE"25V"
PACK_TYPE"0402"
CDS_LIB"pure_quanta";
"B"
$PN"2"4;
"A"
$PN"1"83;
%"UNIVERSAL_GND"
"1","(-2925,5425)","0","pure_quanta_power","I12";
;
CDS_LIB"pure_quanta_power"
HDL_POWER"GND";
"A"5;
%"CONN3_HBB1031L300D8H"
"1","(-6475,4400)","6","pure_quanta","I123";
;
LOCATION"PJ1"
$SEC"1"
CDS_SEC"1"
PART_NUMBER"DFHD03MS162"
MATERIAL"IO"
VALUE"CONN3_HBB1031-L300D-8H"
PART_TYPE"THLF"
CDS_LIB"pure_quanta"
CDS_LMAN_SYM_OUTLINE"-75,175,75,-175"
NEEDS_NO_SIZE"TRUE";
"3"
$PN"3"46;
"2"
$PN"2"45;
"1"
$PN"1"97;
%"UNIVERSAL_GND"
"1","(-6175,4150)","0","pure_quanta_power","I124";
;
HDL_POWER"GND"
CDS_LIB"pure_quanta_power";
"A"97;
%"Q_CAP"
"1","(-2925,5650)","0","pure_quanta","I13";
;
LOCATION"PC470"
$SEC"1"
CDS_SEC"1"
MATERIAL"X6S"
TOLERANCE"20%"
VALUE"10UF"
PART_NUMBER"CH6101MEB01"
VOLTAGE"6.3V"
PACK_TYPE"C0402"
CDS_LIB"pure_quanta";
"B"
$PN"2"5;
"A"
$PN"1"76;
%"Q_RES"
"1","(-8575,1425)","0","pure_quanta","I139";
;
LOCATION"PR282"
$SEC"1"
CDS_SEC"1"
WATTAGE"1/16W"
TOLERANCE"5%"
VALUE"0"
PART_NUMBER"CS00002JB38"
PACK_TYPE"0402LF"
MATERIAL"CHIP"
CDS_LIB"pure_quanta";
"B"
$PN"2"62;
"A"
$PN"1"47;
%"VCC_CORE"
"1","(-2050,6375)","0","pure_quanta_power","I14";
;
HDL_POWER"P3V3_STBY"
CDS_LIB"pure_quanta_power";
"A"96;
%"Q_CAP"
"1","(-8175,1200)","0","pure_quanta","I140";
;
LOCATION"PC461"
$SEC"1"
CDS_SEC"1"
VALUE"1000PF"
MATERIAL"X7R"
VOLTAGE"50V"
PACK_TYPE"0402"
PART_NUMBER"TMP_QCH21006JB10"
TOLERANCE"5%"
CDS_LIB"pure_quanta";
"B"
$PN"2"6;
"A"
$PN"1"62;
%"UNIVERSAL_GND"
"1","(-8175,1000)","0","pure_quanta_power","I141";
;
CDS_LIB"pure_quanta_power"
HDL_POWER"GND";
"A"6;
%"UNIVERSAL_GND"
"1","(-7825,4775)","0","pure_quanta_power","I144";
;
CDS_LIB"pure_quanta_power"
HDL_POWER"GND";
"A"7;
%"UNIVERSAL_GND"
"1","(-7600,4775)","0","pure_quanta_power","I145";
;
CDS_LIB"pure_quanta_power"
HDL_POWER"GND";
"A"8;
%"Q_RES"
"1","(-6025,5350)","0","pure_quanta","I148";
;
LOCATION"PR304"
$SEC"1"
CDS_SEC"1"
WATTAGE"1/16W"
MATERIAL"CHIP"
TOLERANCE"5%"
VALUE"0"
PART_NUMBER"CS00002JB38"
PACK_TYPE"0402LF"
CDS_LIB"pure_quanta";
"B"
$PN"2"43;
"A"
$PN"1"56;
%"Q_RES"
"1","(-6025,5200)","0","pure_quanta","I149";
;
LOCATION"PR305"
$SEC"1"
CDS_SEC"1"
PACK_TYPE"0402LF"
WATTAGE"1/16W"
MATERIAL"CHIP"
TOLERANCE"5%"
VALUE"0"
PART_NUMBER"CS00002JB38"
CDS_LIB"pure_quanta";
"B"
$PN"2"44;
"A"
$PN"1"61;
%"Q_RES"
"1","(-2475,6275)","0","pure_quanta","I151";
;
LOCATION"PR316"
$SEC"1"
CDS_SEC"1"
WATTAGE"1/16W"
MATERIAL"CHIP"
TOLERANCE"1%"
VALUE"1"
PART_NUMBER"CS-1002FB23"
PACK_TYPE"0402LF"
CDS_LIB"pure_quanta";
"B"
$PN"2"96;
"A"
$PN"1"82;
%"MOSFET_PCH_GDS_ESD_PROTECTED"
"1","(-7125,1850)","6","pure_quanta","I154";
;
LOCATION"PQ13"
$SEC"1"
CDS_SEC"1"
MATERIAL"IC"
VALUE"PJA3415AE"
PART_NUMBER"BAM34150008"
NEEDS_NO_SIZE"TRUE"
CDS_LMAN_SYM_OUTLINE"-125,150,125,-150"
CDS_LIB"pure_quanta"
PART_TYPE"SMLF";
"S"
$PN"S"85;
"G"
$PN"G"63;
"D"
$PN"D"27;
%"UNIVERSAL_GND"
"1","(-3200,5875)","0","pure_quanta_power","I155";
;
CDS_LIB"pure_quanta_power"
HDL_POWER"GND";
"A"9;
%"Q_CAP"
"1","(-3200,6125)","0","pure_quanta","I156";
;
LOCATION"PC12"
$SEC"1"
CDS_SEC"1"
MATERIAL"X7R"
TOLERANCE"10%"
VALUE"0.1UF"
PART_NUMBER"CH4104K1B00"
VOLTAGE"25V"
PACK_TYPE"0402"
CDS_LIB"pure_quanta";
"B"
$PN"2"9;
"A"
$PN"1"82;
%"UNIVERSAL_GND"
"1","(-3200,5425)","0","pure_quanta_power","I157";
;
CDS_LIB"pure_quanta_power"
HDL_POWER"GND";
"A"10;
%"Q_CAP"
"1","(-3200,5650)","0","pure_quanta","I158";
;
LOCATION"PC13"
$SEC"1"
CDS_SEC"1"
MATERIAL"X7R"
TOLERANCE"10%"
VALUE"0.1UF"
PART_NUMBER"CH4104K1B00"
VOLTAGE"25V"
PACK_TYPE"0402"
CDS_LIB"pure_quanta";
"B"
$PN"2"10;
"A"
$PN"1"76;
%"VCC_CORE"
"1","(-6275,1800)","0","pure_quanta_power","I168";
;
HDL_POWER"PVDD18_S5_P0"
CDS_LIB"pure_quanta_power";
"A"95;
%"UNIVERSAL_GND"
"1","(-5275,1725)","1","pure_quanta_power","I169";
;
CDS_LIB"pure_quanta_power"
HDL_POWER"GND";
"A"11;
%"Q_CAP"
"2","(-5675,1725)","0","pure_quanta","I170";
;
LOCATION"PC466"
$SEC"1"
CDS_SEC"1"
PART_NUMBER"CH5101K1B01"
MATERIAL"X7R"
TOLERANCE"10%"
VALUE"1UF"
VOLTAGE"6.3V"
PACK_TYPE"0402"
CDS_LIB"pure_quanta";
"A"
$PN"1"95;
"B"
$PN"2"11;
%"VCC_CORE"
"1","(-6575,2525)","0","pure_quanta_power","I172";
;
HDL_POWER"PVDD18_S5_P0"
CDS_LIB"pure_quanta_power";
"A"94;
%"Q_RES"
"1","(-5975,2100)","0","pure_quanta","I173";
;
LOCATION"PR301"
$SEC"1"
CDS_SEC"1"
WATTAGE"1/16W"
MATERIAL"CHIP"
TOLERANCE"5%"
VALUE"0"
PART_NUMBER"CS00002JB38"
PACK_TYPE"0402LF"
CDS_LIB"pure_quanta";
"B"
$PN"2"66;
"A"
$PN"1"65;
%"Q_RES"
"1","(-5975,2250)","0","pure_quanta","I174";
;
LOCATION"PR315"
$SEC"1"
CDS_SEC"1"
WATTAGE"1/16W"
MATERIAL"CHIP"
TOLERANCE"5%"
VALUE"0"
PART_NUMBER"CS00002JB38"
PACK_TYPE"0402LF"
CDS_LIB"pure_quanta";
"B"
$PN"2"60;
"A"
$PN"1"64;
%"Q_RES"
"1","(-6125,2400)","0","pure_quanta","I175";
;
LOCATION"PR317"
$SEC"1"
CDS_SEC"1"
WATTAGE"1/16W"
MATERIAL"CHIP"
TOLERANCE"1%"
VALUE"1K"
PART_NUMBER"TMP_QCS21002FB24"
PACK_TYPE"0402LF"
CDS_LIB"pure_quanta";
"B"
$PN"2"60;
"A"
$PN"1"94;
%"Q_RES"
"1","(-5425,1975)","0","pure_quanta","I176";
;
LOCATION"PR313"
$SEC"1"
CDS_SEC"1"
WATTAGE"1/16W"
MATERIAL"CHIP"
TOLERANCE"1%"
VALUE"1K"
PART_NUMBER"TMP_QCS21002FB24"
PACK_TYPE"0402LF"
CDS_LIB"pure_quanta";
"B"
$PN"2"66;
"A"
$PN"1"95;
%"Q_CAP"
"1","(-7600,5025)","0","pure_quanta","I214";
;
LOCATION"PC302"
$SEC"1"
CDS_SEC"1"
PACK_TYPE"0402"
PART_NUMBER"CH01006JB08"
MATERIAL"EMPTY"
TOLERANCE"5%"
VALUE"10PF"
VOLTAGE"50V"
CDS_LIB"pure_quanta";
"B"
$PN"2"8;
"A"
$PN"1"40;
%"Q_CAP"
"1","(-7825,5025)","0","pure_quanta","I215";
;
LOCATION"PC299"
$SEC"1"
CDS_SEC"1"
VOLTAGE"50V"
MATERIAL"EMPTY"
TOLERANCE"5%"
PACK_TYPE"0402"
VALUE"10PF"
CDS_LIB"pure_quanta"
PART_NUMBER"CH01006JB08";
"B"
$PN"2"7;
"A"
$PN"1"42;
%"Q_CAP"
"1","(-8050,5025)","0","pure_quanta","I216";
;
LOCATION"PC298"
$SEC"1"
CDS_SEC"1"
MATERIAL"EMPTY"
TOLERANCE"5%"
VALUE"10PF"
VOLTAGE"50V"
PACK_TYPE"0402"
CDS_LIB"pure_quanta"
PART_NUMBER"CH01006JB08";
"B"
$PN"2"12;
"A"
$PN"1"56;
%"UNIVERSAL_GND"
"1","(-8050,4775)","0","pure_quanta_power","I217";
;
CDS_LIB"pure_quanta_power"
HDL_POWER"GND";
"A"12;
%"Q_RES"
"1","(-2925,2900)","0","pure_quanta","I232";
;
LOCATION"PR440"
$SEC"1"
CDS_SEC"1"
WATTAGE"1/16W"
VALUE"0"
TOLERANCE"5%"
PART_NUMBER"CS00002JB38"
PACK_TYPE"0402LF"
MATERIAL"CHIP"
CDS_LIB"pure_quanta";
"B"
$PN"2"93;
"A"
$PN"1"72;
%"UNIVERSAL_GND"
"1","(-2575,2750)","0","pure_quanta_power","I233";
;
CDS_LIB"pure_quanta_power"
HDL_POWER"GND";
"A"93;
%"UNIVERSAL_GND"
"1","(-2575,3050)","0","pure_quanta_power","I234";
;
CDS_LIB"pure_quanta_power"
HDL_POWER"GND";
"A"92;
%"Q_RES"
"1","(-2925,3200)","0","pure_quanta","I235";
;
LOCATION"PR531"
$SEC"1"
CDS_SEC"1"
PART_NUMBER"CS00002JB38"
WATTAGE"1/16W"
MATERIAL"CHIP"
VALUE"0"
TOLERANCE"5%"
PACK_TYPE"0402LF"
CDS_LIB"pure_quanta";
"B"
$PN"2"92;
"A"
$PN"1"28;
%"UNIVERSAL_GND"
"1","(-2575,2475)","0","pure_quanta_power","I242";
;
CDS_LIB"pure_quanta_power"
HDL_POWER"GND";
"A"91;
%"Q_RES"
"1","(-2925,2600)","0","pure_quanta","I243";
;
LOCATION"PR441"
$SEC"1"
CDS_SEC"1"
PACK_TYPE"0402LF"
TOLERANCE"5%"
VALUE"0"
WATTAGE"1/16W"
MATERIAL"CHIP"
PART_NUMBER"CS00002JB38"
CDS_LIB"pure_quanta";
"B"
$PN"2"91;
"A"
$PN"1"34;
%"Q_RES"
"2","(-5675,450)","0","pure_quanta","I244";
;
LOCATION"PR599"
$SEC"1"
CDS_SEC"1"
WATTAGE"1/16W"
MATERIAL"EMPTY"
TOLERANCE"1%"
VALUE"4.99K"
PART_NUMBER"CS24992FB07"
PACK_TYPE"0402LF"
CDS_LIB"pure_quanta";
"A"
$PN"1"32;
"B"
$PN"2"13;
%"UNIVERSAL_GND"
"1","(-5675,250)","0","pure_quanta_power","I245";
;
CDS_LIB"pure_quanta_power"
HDL_POWER"GND";
"A"13;
%"Q_RES"
"2","(-7100,1375)","0","pure_quanta","I3";
;
LOCATION"PR292"
$SEC"1"
CDS_SEC"1"
WATTAGE"1/16W"
MATERIAL"CHIP"
TOLERANCE"1%"
VALUE"681"
PART_NUMBER"CS16812FB02"
PACK_TYPE"0402LF"
CDS_LIB"pure_quanta";
"A"
$PN"1"27;
"B"
$PN"2"88;
%"Q_CAP"
"1","(-2750,1025)","0","pure_quanta","I35";
;
LOCATION"PC472"
$SEC"1"
CDS_SEC"1"
MATERIAL"X7R"
TOLERANCE"10%"
VALUE"470PF"
PART_NUMBER"TMP_QCH14706KB18"
VOLTAGE"50V"
PACK_TYPE"0402"
CDS_LIB"pure_quanta";
"B"
$PN"2"15;
"A"
$PN"1"39;
%"Q_CAP"
"1","(-3375,700)","0","pure_quanta","I36";
;
LOCATION"PC469"
$SEC"1"
CDS_SEC"1"
MATERIAL"X7R"
TOLERANCE"10%"
VALUE"470PF"
PART_NUMBER"TMP_QCH14706KB18"
VOLTAGE"50V"
PACK_TYPE"0402"
CDS_LIB"pure_quanta";
"B"
$PN"2"14;
"A"
$PN"1"68;
%"UNIVERSAL_GND"
"1","(-3375,425)","0","pure_quanta_power","I37";
;
CDS_LIB"pure_quanta_power"
HDL_POWER"GND";
"A"14;
%"UNIVERSAL_GND"
"1","(-2750,775)","0","pure_quanta_power","I38";
;
CDS_LIB"pure_quanta_power"
HDL_POWER"GND";
"A"15;
%"Q_RES"
"2","(-7775,2025)","0","pure_quanta","I4";
;
LOCATION"PR285"
$SEC"1"
CDS_SEC"1"
WATTAGE"1/16W"
MATERIAL"CHIP"
TOLERANCE"1%"
VALUE"1K"
PART_NUMBER"TMP_QCS21002FB24"
PACK_TYPE"0402LF"
CDS_LIB"pure_quanta";
"A"
$PN"1"85;
"B"
$PN"2"63;
%"Q_RES"
"1","(-6125,6375)","0","pure_quanta","I41";
;
LOCATION"PR300"
$SEC"1"
CDS_SEC"1"
PACK_TYPE"0402LF"
VALUE"1K"
WATTAGE"1/16W"
PART_NUMBER"TMP_QCS21002FB24"
MATERIAL"CHIP"
TOLERANCE"1%"
CDS_LIB"pure_quanta";
"B"
$PN"2"36;
"A"
$PN"1"89;
%"Q_CAP"
"2","(-5250,6375)","0","pure_quanta","I42";
;
LOCATION"PC467"
$SEC"1"
CDS_SEC"1"
MATERIAL"EMPTY"
VALUE"1000PF"
VOLTAGE"50V"
TOLERANCE"5%"
PART_NUMBER"TMP_QCH21006JB10"
PACK_TYPE"0402"
CDS_LIB"pure_quanta";
"A"
$PN"1"36;
"B"
$PN"2"90;
%"Q_RES"
"1","(-5900,6100)","0","pure_quanta","I43";
;
LOCATION"PR311"
$SEC"1"
CDS_SEC"1"
WATTAGE"1/16W"
TOLERANCE"5%"
PART_NUMBER"CS00002JB38"
PACK_TYPE"0402LF"
VALUE"0"
MATERIAL"CHIP"
CDS_LIB"pure_quanta";
"B"
$PN"2"36;
"A"
$PN"1"49;
%"UNIVERSAL_GND"
"1","(-5000,6300)","0","pure_quanta_power","I44";
;
CDS_LIB"pure_quanta_power"
HDL_POWER"GND";
"A"90;
%"VCC_CORE"
"1","(-6525,6500)","0","pure_quanta_power","I46";
;
HDL_POWER"P3V3_STBY"
CDS_LIB"pure_quanta_power";
"A"89;
%"Q_RES"
"1","(-5900,5950)","0","pure_quanta","I47";
;
LOCATION"PR312"
$SEC"1"
CDS_SEC"1"
WATTAGE"1/16W"
MATERIAL"CHIP"
TOLERANCE"5%"
VALUE"0"
PACK_TYPE"0402LF"
PART_NUMBER"CS00002JB38"
CDS_LIB"pure_quanta";
"B"
$PN"2"41;
"A"
$PN"1"48;
%"Q_CAP"
"2","(-5225,5825)","0","pure_quanta","I49";
;
LOCATION"PC468"
$SEC"1"
CDS_SEC"1"
VALUE"1000PF"
PACK_TYPE"0402"
VOLTAGE"50V"
MATERIAL"X7R"
TOLERANCE"5%"
PART_NUMBER"TMP_QCH21006JB10"
CDS_LIB"pure_quanta";
"A"
$PN"1"41;
"B"
$PN"2"87;
%"UNIVERSAL_GND"
"1","(-7100,1175)","0","pure_quanta_power","I5";
;
CDS_LIB"pure_quanta_power"
HDL_POWER"GND";
"A"88;
%"UNIVERSAL_GND"
"1","(-5000,5750)","0","pure_quanta_power","I50";
;
CDS_LIB"pure_quanta_power"
HDL_POWER"GND";
"A"87;
%"Q_RES"
"2","(-7975,5975)","0","pure_quanta","I55";
;
LOCATION"PR287"
$SEC"1"
CDS_SEC"1"
WATTAGE"1/16W"
MATERIAL"EMPTY"
TOLERANCE"1%"
PACK_TYPE"0402LF"
VALUE"1K"
CDS_LIB"pure_quanta"
PART_NUMBER"TMP_QCS21002FB24";
"A"
$PN"1"86;
"B"
$PN"2"56;
%"Q_RES"
"2","(-8325,5975)","0","pure_quanta","I56";
;
LOCATION"PR284"
$SEC"1"
CDS_SEC"1"
WATTAGE"1/16W"
MATERIAL"EMPTY"
TOLERANCE"1%"
VALUE"1K"
PACK_TYPE"0402LF"
CDS_LIB"pure_quanta"
PART_NUMBER"TMP_QCS21002FB24";
"A"
$PN"1"86;
"B"
$PN"2"61;
%"Q_RES"
"2","(-7675,5975)","0","pure_quanta","I57";
;
LOCATION"PR289"
$SEC"1"
CDS_SEC"1"
WATTAGE"1/16W"
MATERIAL"EMPTY"
VALUE"1K"
PACK_TYPE"0402LF"
TOLERANCE"1%"
CDS_LIB"pure_quanta"
PART_NUMBER"TMP_QCS21002FB24";
"A"
$PN"1"86;
"B"
$PN"2"42;
%"Q_RES"
"2","(-7400,5975)","0","pure_quanta","I58";
;
LOCATION"PR293"
$SEC"1"
CDS_SEC"1"
WATTAGE"1/16W"
MATERIAL"EMPTY"
TOLERANCE"1%"
VALUE"1K"
PACK_TYPE"0402LF"
PART_NUMBER"TMP_QCS21002FB24"
CDS_LIB"pure_quanta";
"A"
$PN"1"86;
"B"
$PN"2"40;
%"VCC_CORE"
"1","(-8325,6275)","0","pure_quanta_power","I59";
;
HDL_POWER"PVDD18_S5_P0"
CDS_LIB"pure_quanta_power";
"A"86;
%"VCC_CORE"
"1","(-7775,2250)","0","pure_quanta_power","I6";
;
HDL_POWER"P3V3_STBY"
CDS_LIB"pure_quanta_power";
"A"85;
%"Q_RES"
"2","(-8275,5025)","0","pure_quanta","I62";
;
LOCATION"PR286"
$SEC"1"
CDS_SEC"1"
PACK_TYPE"0402LF"
MATERIAL"EMPTY"
WATTAGE"1/16W"
TOLERANCE"1%"
VALUE"1K"
CDS_LIB"pure_quanta"
PART_NUMBER"TMP_QCS21002FB24";
"A"
$PN"1"56;
"B"
$PN"2"17;
%"Q_RES"
"2","(-8525,5025)","0","pure_quanta","I63";
;
LOCATION"PR283"
$SEC"1"
CDS_SEC"1"
WATTAGE"1/16W"
MATERIAL"CHIP"
TOLERANCE"5%"
PACK_TYPE"0402LF"
VALUE"1K"
CDS_LIB"pure_quanta"
PART_NUMBER"TMP_QCS21002JB34";
"A"
$PN"1"61;
"B"
$PN"2"16;
%"UNIVERSAL_GND"
"1","(-8525,4775)","0","pure_quanta_power","I64";
;
CDS_LIB"pure_quanta_power"
HDL_POWER"GND";
"A"16;
%"UNIVERSAL_GND"
"1","(-8275,4775)","0","pure_quanta_power","I65";
;
CDS_LIB"pure_quanta_power"
HDL_POWER"GND";
"A"17;
%"Q_RES"
"1","(-5925,4950)","0","pure_quanta","I66";
;
LOCATION"PR308"
$SEC"1"
CDS_SEC"1"
PART_NUMBER"CS00002JB38"
MATERIAL"CHIP"
TOLERANCE"5%"
PACK_TYPE"0402LF"
WATTAGE"1/16W"
VALUE"0"
CDS_LIB"pure_quanta";
"B"
$PN"2"57;
"A"
$PN"1"46;
%"Q_RES"
"1","(-5925,4800)","0","pure_quanta","I67";
;
LOCATION"PR309"
$SEC"1"
CDS_SEC"1"
VALUE"0"
PART_NUMBER"CS00002JB38"
MATERIAL"CHIP"
PACK_TYPE"0402LF"
WATTAGE"1/16W"
TOLERANCE"5%"
CDS_LIB"pure_quanta";
"B"
$PN"2"59;
"A"
$PN"1"45;
%"Q_RES"
"1","(-5925,4650)","0","pure_quanta","I68";
;
LOCATION"PR310"
$SEC"1"
CDS_SEC"1"
PART_NUMBER"CS00002JB38"
TOLERANCE"5%"
VALUE"0"
MATERIAL"CHIP"
WATTAGE"1/16W"
PACK_TYPE"0402LF"
CDS_LIB"pure_quanta";
"B"
$PN"2"58;
"A"
$PN"1"52;
%"RAA229620GNPHA0"
"1","(-4325,3350)","0","pure_quanta","I7";
;
LOCATION"PU42"
SEC"1"
PART_TYPE"SMLF"
VALUE"RAA229620GNP#HA0"
MATERIAL"IC"
PART_NUMBER"AR0T6GPV005"
SEC_TYPE""
CDS_LIB"pure_quanta"
NEEDS_NO_SIZE"TRUE"
CDS_LMAN_SYM_OUTLINE"-550,2850,500,-2850";
"CS10"
$PN"28"55;
"PWM10"
$PN"11"54;
"CS9"
$PN"29"79;
"PWM9"
$PN"10"78;
"CS8"
$PN"30"81;
"PWM8"
$PN"9"80;
"CS7"
$PN"31"74;
"PWM7"
$PN"8"75;
"CS0"
$PN"38"38;
"PWM0"
$PN"1"69;
"TEMP1"
$PN"43"39;
"EN1||ADDR_CFG"
$PN"42"27;
"TH_GND"
$PN"TH"84;
"OCP_L \B"
$PN"41"66;
"CS2"
$PN"36"33;
"PWM2"
$PN"3"26;
"CS3"
$PN"35"34;
"PWM3"
$PN"4"35;
"PWM11"
$PN"12"77;
"CS1"
$PN"37"70;
"RGND1"
$PN"39"22;
"VSEN1"
$PN"40"67;
"VDDIO"
$PN"19"95;
"TEMP0"
$PN"44"68;
"VINSEN"
$PN"46"32;
"VMON||IINSEN"
$PN"45"83;
"VCCS"
$PN"48"76;
"PWM6"
$PN"7"30;
"PG0"
$PN"16"36;
"PWM1"
$PN"2"73;
"VSEN0"
$PN"25"37;
"PWM5"
$PN"6"71;
"PWM4"
$PN"5"50;
"PMSDA"
$PN"13"59;
"RGND0"
$PN"26"24;
"EN0"
$PN"17"41;
"NPMALERT \B"
$PN"15"58;
"SVD"
$PN"21"42;
"PG1"
$PN"20"31;
"CS4"
$PN"34"72;
"CS5"
$PN"33"28;
"RESET_L \B"
$PN"18"60;
"SVTO"
$PN"23"43;
"CS6"
$PN"32"29;
"SVC"
$PN"22"40;
"PMSCL"
$PN"14"57;
"SVTI"
$PN"24"44;
"VCC"
$PN"47"82;
"CS11"
$PN"27"53;
%"Q_CAP"
"1","(-5750,3925)","0","pure_quanta","I76";
;
LOCATION"PC463"
$SEC"1"
CDS_SEC"1"
PART_NUMBER"TMP_QCH2336K1B12"
PACK_TYPE"0402"
MATERIAL"X7R"
VALUE"3300PF"
VOLTAGE"50V"
TOLERANCE"10%"
CDS_LIB"pure_quanta";
"B"
$PN"2"24;
"A"
$PN"1"37;
%"Q_RES"
"1","(-6025,4050)","0","pure_quanta","I77";
;
LOCATION"PR306"
$SEC"1"
CDS_SEC"1"
PACK_TYPE"0402LF"
PART_NUMBER"TMP_QCS01002FB21"
VALUE"10"
MATERIAL"CHIP"
TOLERANCE"1%"
WATTAGE"1/16W"
CDS_LIB"pure_quanta";
"B"
$PN"2"37;
"A"
$PN"1"25;
%"Q_CAP"
"1","(-2900,6125)","0","pure_quanta","I8";
;
LOCATION"PC471"
$SEC"1"
CDS_SEC"1"
MATERIAL"X6S"
TOLERANCE"10%"
VALUE"1UF"
PART_NUMBER"CH5103KEB01"
VOLTAGE"16V"
PACK_TYPE"C0402"
CDS_LIB"pure_quanta";
"B"
$PN"2"1;
"A"
$PN"1"82;
%"Q_RES"
"2","(-7050,4250)","0","pure_quanta","I81";
;
LOCATION"PR294"
$SEC"1"
CDS_SEC"1"
WATTAGE"1/16W"
PART_NUMBER"CS04992FB31"
MATERIAL"CHIP"
PACK_TYPE"0402LF"
VALUE"49.9"
TOLERANCE"1%"
CDS_LIB"pure_quanta";
"A"
$PN"1"19;
"B"
$PN"2"25;
%"Q_RES"
"2","(-7050,3625)","0","pure_quanta","I82";
;
LOCATION"PR295"
$SEC"1"
CDS_SEC"1"
PACK_TYPE"0402LF"
WATTAGE"1/16W"
MATERIAL"CHIP"
PART_NUMBER"CS04992FB31"
VALUE"49.9"
TOLERANCE"1%"
CDS_LIB"pure_quanta";
"A"
$PN"1"24;
"B"
$PN"2"18;
%"UNIVERSAL_GND"
"1","(-7050,3425)","0","pure_quanta_power","I83";
;
CDS_LIB"pure_quanta_power"
HDL_POWER"GND";
"A"18;
%"VCC_CORE"
"1","(-7050,4450)","0","pure_quanta_power","I84";
;
HDL_POWER"PVDDCR_CPU0_P0"
CDS_LIB"pure_quanta_power";
"A"19;
%"VCC_CORE"
"1","(-7050,3300)","0","pure_quanta_power","I85";
;
HDL_POWER"PVDDCR_SOC_P0"
CDS_LIB"pure_quanta_power";
"A"20;
%"Q_RES"
"2","(-7050,3125)","0","pure_quanta","I86";
;
LOCATION"PR296"
$SEC"1"
CDS_SEC"1"
WATTAGE"1/16W"
MATERIAL"CHIP"
PART_NUMBER"CS04992FB31"
PACK_TYPE"0402LF"
VALUE"49.9"
TOLERANCE"1%"
CDS_LIB"pure_quanta";
"A"
$PN"1"20;
"B"
$PN"2"23;
%"Q_CAP"
"1","(-5675,2825)","0","pure_quanta","I87";
;
LOCATION"PC464"
$SEC"1"
CDS_SEC"1"
MATERIAL"X7R"
TOLERANCE"10%"
VALUE"3300PF"
PART_NUMBER"TMP_QCH2336K1B12"
VOLTAGE"50V"
PACK_TYPE"0402"
CDS_LIB"pure_quanta";
"B"
$PN"2"22;
"A"
$PN"1"67;
%"Q_RES"
"1","(-5950,2950)","0","pure_quanta","I88";
;
LOCATION"PR307"
$SEC"1"
CDS_SEC"1"
WATTAGE"1/16W"
MATERIAL"CHIP"
TOLERANCE"1%"
VALUE"10"
PART_NUMBER"TMP_QCS01002FB21"
PACK_TYPE"0402LF"
CDS_LIB"pure_quanta";
"B"
$PN"2"67;
"A"
$PN"1"23;
%"Q_RES"
"2","(-7050,2525)","0","pure_quanta","I90";
;
LOCATION"PR297"
$SEC"1"
CDS_SEC"1"
WATTAGE"1/16W"
MATERIAL"CHIP"
PART_NUMBER"CS04992FB31"
PACK_TYPE"0402LF"
VALUE"49.9"
TOLERANCE"1%"
CDS_LIB"pure_quanta";
"A"
$PN"1"22;
"B"
$PN"2"21;
%"UNIVERSAL_GND"
"1","(-7050,2325)","0","pure_quanta_power","I91";
;
CDS_LIB"pure_quanta_power"
HDL_POWER"GND";
"A"21;
%"UNIVERSAL_GND"
"1","(-5100,450)","0","pure_quanta_power","I99";
;
CDS_LIB"pure_quanta_power"
HDL_POWER"GND";
"A"84;
END.
